(kicad_pcb
	(version 20260206)
	(generator "pcbnew")
	(generator_version "10.0")
	(general
		(thickness 1.21888)
		(legacy_teardrops no)
	)
	(paper "A4")
	(title_block
		(title "timecard-v9 — TimeCard-DC-V9_EXP.PcbDoc")
		(comment 1 "Time Appliance Project (Time Card) / footprints 7-9 of 402")
	)
	(layers
		(0 "F.Cu" signal "TOP")
		(4 "In1.Cu" signal "SGND")
		(6 "In2.Cu" signal "IN1")
		(8 "In3.Cu" signal "IN2")
		(10 "In4.Cu" signal "SGND1")
		(2 "B.Cu" signal "BOTTOM")
		(9 "F.Adhes" user "F.Adhesive")
		(11 "B.Adhes" user "B.Adhesive")
		(13 "F.Paste" user "Top Paste")
		(15 "B.Paste" user "Bottom Paste")
		(5 "F.SilkS" user "Top Overlay")
		(7 "B.SilkS" user "Bottom Overlay")
		(1 "F.Mask" user "Top Solder")
		(3 "B.Mask" user "Bottom Solder")
		(17 "Dwgs.User" user "User.Drawings")
		(19 "Cmts.User" user "User.Comments")
		(21 "Eco1.User" user "User.Eco1")
		(23 "Eco2.User" user "User.Eco2")
		(25 "Edge.Cuts" user)
		(27 "Margin" user)
		(31 "F.CrtYd" user "Top Courtyard")
		(29 "B.CrtYd" user "Bottom Courtyard")
		(35 "F.Fab" user "Top Component Center")
		(33 "B.Fab" user "Bottom Component Center")
	)
	(footprint "FPGA_CONN:SingleFPGAConn"
		(locked yes)
		(layer "F.Cu")
		(at 138.43638 129.97062)
		(property "Reference" "J36"
			(at -1.77665 -22.527499 0)
			(unlocked yes)
			(layer "F.SilkS")
			(effects
				(font
					(size 0.762 0.762)
					(thickness 0.2286)
				)
			)
		)
		(property "Value" "Single FPGA Conn"
			(at 9.25452 3.621231 0)
			(unlocked yes)
			(layer "F.SilkS")
			(hide yes)
			(effects
				(font
					(size 0.762 0.762)
					(thickness 0.2286)
				)
			)
		)
		(sheetname "07-FPGA")
		(sheetfile "07-FPGA.kicad_sch")
		(duplicate_pad_numbers_are_jumpers no)
		(fp_line
			(start -2 -20.69999)
			(end -1.40005 -20.69999)
			(stroke
				(width 0.15011)
				(type solid)
			)
			(layer "F.SilkS")
		)
		(fp_line
			(start -2 -20.03298)
			(end -2 -20.69999)
			(stroke
				(width 0.15011)
				(type solid)
			)
			(layer "F.SilkS")
		)
		(fp_line
			(start -2 0.70002)
			(end -2 0.03302)
			(stroke
				(width 0.15011)
				(type solid)
			)
			(layer "F.SilkS")
		)
		(fp_line
			(start -2 0.70002)
			(end -1.40005 0.70002)
			(stroke
				(width 0.15011)
				(type solid)
			)
			(layer "F.SilkS")
		)
		(fp_line
			(start -1.40005 -21.2499)
			(end 1.40004 -21.2499)
			(stroke
				(width 0.15011)
				(type solid)
			)
			(layer "F.SilkS")
		)
		(fp_line
			(start -1.40005 -20.69999)
			(end -1.40005 -21.2499)
			(stroke
				(width 0.15011)
				(type solid)
			)
			(layer "F.SilkS")
		)
		(fp_line
			(start -1.40005 1.24993)
			(end -1.40005 0.70002)
			(stroke
				(width 0.15011)
				(type solid)
			)
			(layer "F.SilkS")
		)
		(fp_line
			(start -1.40005 1.24993)
			(end 1.40004 1.24993)
			(stroke
				(width 0.15011)
				(type solid)
			)
			(layer "F.SilkS")
		)
		(fp_line
			(start 1.40004 -21.2499)
			(end 1.99999 -20.69999)
			(stroke
				(width 0.15011)
				(type solid)
			)
			(layer "F.SilkS")
		)
		(fp_line
			(start 1.40004 1.24993)
			(end 1.99999 0.70002)
			(stroke
				(width 0.15011)
				(type solid)
			)
			(layer "F.SilkS")
		)
		(fp_line
			(start 1.99999 -20.03298)
			(end 1.99999 -20.69999)
			(stroke
				(width 0.15011)
				(type solid)
			)
			(layer "F.SilkS")
		)
		(fp_line
			(start 1.99999 0.70002)
			(end 1.99999 0.03302)
			(stroke
				(width 0.15011)
				(type solid)
			)
			(layer "F.SilkS")
		)
		(fp_circle
			(center 3.5052 -0.22454)
			(end 3.5052 -0.42469)
			(stroke
				(width 0.40005)
				(type solid)
			)
			(fill no)
			(layer "F.SilkS")
		)
		(pad "1" smd rect
			(at 2.02488 -0.24994)
			(size 1.54991 0.24994)
			(layers "F.Cu" "F.Mask" "F.Paste")
			(net "GPS2_TX_FPGA")
		)
		(pad "2" smd rect
			(at -2.02489 -0.24994)
			(size 1.54991 0.24994)
			(layers "F.Cu" "F.Mask" "F.Paste")
			(net "GPS2_RX_FPGA")
		)
		(pad "3" smd rect
			(at 2.02488 -0.75007)
			(size 1.54991 0.24994)
			(layers "F.Cu" "F.Mask" "F.Paste")
		)
		(pad "4" smd rect
			(at -2.02489 -0.75007)
			(size 1.54991 0.24994)
			(layers "F.Cu" "F.Mask" "F.Paste")
		)
		(pad "5" smd rect
			(at 2.02488 -1.24994)
			(size 1.54991 0.24994)
			(layers "F.Cu" "F.Mask" "F.Paste")
			(net "GPS2_TP1")
		)
		(pad "6" smd rect
			(at -2.02489 -1.24994)
			(size 1.54991 0.24994)
			(layers "F.Cu" "F.Mask" "F.Paste")
		)
		(pad "7" smd rect
			(at 2.02488 -1.75006)
			(size 1.54991 0.24994)
			(layers "F.Cu" "F.Mask" "F.Paste")
			(net "GPS2_TP2")
		)
		(pad "8" smd rect
			(at -2.02489 -1.75006)
			(size 1.54991 0.24994)
			(layers "F.Cu" "F.Mask" "F.Paste")
		)
		(pad "9" smd rect
			(at 2.02488 -2.24994)
			(size 1.54991 0.24994)
			(layers "F.Cu" "F.Mask" "F.Paste")
			(net "GND")
		)
		(pad "10" smd rect
			(at -2.02489 -2.24994)
			(size 1.54991 0.24994)
			(layers "F.Cu" "F.Mask" "F.Paste")
			(net "GND")
		)
		(pad "11" smd rect
			(at 2.02488 -2.75006)
			(size 1.54991 0.24994)
			(layers "F.Cu" "F.Mask" "F.Paste")
			(net "GPS2_RST")
		)
		(pad "12" smd rect
			(at -2.02489 -2.75006)
			(size 1.54991 0.24994)
			(layers "F.Cu" "F.Mask" "F.Paste")
			(net "IO_LED1")
		)
		(pad "13" smd rect
			(at 2.02488 -3.24993)
			(size 1.54991 0.24994)
			(layers "F.Cu" "F.Mask" "F.Paste")
		)
		(pad "14" smd rect
			(at -2.02489 -3.24993)
			(size 1.54991 0.24994)
			(layers "F.Cu" "F.Mask" "F.Paste")
			(net "IO_LED2")
		)
		(pad "15" smd rect
			(at 2.02488 -3.75006)
			(size 1.54991 0.24994)
			(layers "F.Cu" "F.Mask" "F.Paste")
		)
		(pad "16" smd rect
			(at -2.02489 -3.75006)
			(size 1.54991 0.24994)
			(layers "F.Cu" "F.Mask" "F.Paste")
			(net "IO_LED3")
		)
		(pad "17" smd rect
			(at 2.02488 -4.24993)
			(size 1.54991 0.24994)
			(layers "F.Cu" "F.Mask" "F.Paste")
		)
		(pad "18" smd rect
			(at -2.02489 -4.24993)
			(size 1.54991 0.24994)
			(layers "F.Cu" "F.Mask" "F.Paste")
			(net "IO_LED4")
		)
		(pad "19" smd rect
			(at 2.02488 -4.75006)
			(size 1.54991 0.24994)
			(layers "F.Cu" "F.Mask" "F.Paste")
			(net "GND")
		)
		(pad "20" smd rect
			(at -2.02489 -4.75006)
			(size 1.54991 0.24994)
			(layers "F.Cu" "F.Mask" "F.Paste")
			(net "GND")
		)
		(pad "21" smd rect
			(at 2.02488 -5.24993)
			(size 1.54991 0.24994)
			(layers "F.Cu" "F.Mask" "F.Paste")
			(net "PCIE_PERST")
		)
		(pad "22" smd rect
			(at -2.02489 -5.24993)
			(size 1.54991 0.24994)
			(layers "F.Cu" "F.Mask" "F.Paste")
		)
		(pad "23" smd rect
			(at 2.02488 -5.75006)
			(size 1.54991 0.24994)
			(layers "F.Cu" "F.Mask" "F.Paste")
			(net "KEY1")
		)
		(pad "24" smd rect
			(at -2.02489 -5.75006)
			(size 1.54991 0.24994)
			(layers "F.Cu" "F.Mask" "F.Paste")
		)
		(pad "25" smd rect
			(at 2.02488 -6.24993)
			(size 1.54991 0.24994)
			(layers "F.Cu" "F.Mask" "F.Paste")
		)
		(pad "26" smd rect
			(at -2.02489 -6.24993)
			(size 1.54991 0.24994)
			(layers "F.Cu" "F.Mask" "F.Paste")
		)
		(pad "27" smd rect
			(at 2.02488 -6.75005)
			(size 1.54991 0.24994)
			(layers "F.Cu" "F.Mask" "F.Paste")
		)
		(pad "28" smd rect
			(at -2.02489 -6.75005)
			(size 1.54991 0.24994)
			(layers "F.Cu" "F.Mask" "F.Paste")
		)
		(pad "29" smd rect
			(at 2.02488 -7.24993)
			(size 1.54991 0.24994)
			(layers "F.Cu" "F.Mask" "F.Paste")
			(net "GND")
		)
		(pad "30" smd rect
			(at -2.02489 -7.24993)
			(size 1.54991 0.24994)
			(layers "F.Cu" "F.Mask" "F.Paste")
			(net "GND")
		)
		(pad "31" smd rect
			(at 2.02488 -7.75005)
			(size 1.54991 0.24994)
			(layers "F.Cu" "F.Mask" "F.Paste")
			(net "ANT1_IO_OUT")
		)
		(pad "32" smd rect
			(at -2.02489 -7.75005)
			(size 1.54991 0.24994)
			(layers "F.Cu" "F.Mask" "F.Paste")
			(net "EXT_GPIO_7")
		)
		(pad "33" smd rect
			(at 2.02488 -8.24992)
			(size 1.54991 0.24994)
			(layers "F.Cu" "F.Mask" "F.Paste")
			(net "ANT1_IO_IN")
		)
		(pad "34" smd rect
			(at -2.02489 -8.24992)
			(size 1.54991 0.24994)
			(layers "F.Cu" "F.Mask" "F.Paste")
			(net "EXT_GPIO_8")
		)
		(pad "35" smd rect
			(at 2.02488 -8.75005)
			(size 1.54991 0.24994)
			(layers "F.Cu" "F.Mask" "F.Paste")
			(net "ANT2_IO_OUT")
		)
		(pad "36" smd rect
			(at -2.02489 -8.75005)
			(size 1.54991 0.24994)
			(layers "F.Cu" "F.Mask" "F.Paste")
			(net "EXT_GPIO_9")
		)
		(pad "37" smd rect
			(at 2.02488 -9.24992)
			(size 1.54991 0.24994)
			(layers "F.Cu" "F.Mask" "F.Paste")
			(net "ANT2_IO_IN")
		)
		(pad "38" smd rect
			(at -2.02489 -9.24992)
			(size 1.54991 0.24994)
			(layers "F.Cu" "F.Mask" "F.Paste")
			(net "EXT_GPIO_10")
		)
		(pad "39" smd rect
			(at 2.02488 -9.75005)
			(size 1.54991 0.24994)
			(layers "F.Cu" "F.Mask" "F.Paste")
			(net "GND")
		)
		(pad "40" smd rect
			(at -2.02489 -9.75005)
			(size 1.54991 0.24994)
			(layers "F.Cu" "F.Mask" "F.Paste")
			(net "GND")
		)
		(pad "41" smd rect
			(at 2.02488 -10.24992)
			(size 1.54991 0.24994)
			(layers "F.Cu" "F.Mask" "F.Paste")
			(net "ANT3_IO_OUT")
		)
		(pad "42" smd rect
			(at -2.02489 -10.24992)
			(size 1.54991 0.24994)
			(layers "F.Cu" "F.Mask" "F.Paste")
			(net "EXT_GPIO_1")
		)
		(pad "43" smd rect
			(at 2.02488 -10.75005)
			(size 1.54991 0.24994)
			(layers "F.Cu" "F.Mask" "F.Paste")
			(net "ANT3_IO_IN")
		)
		(pad "44" smd rect
			(at -2.02489 -10.75005)
			(size 1.54991 0.24994)
			(layers "F.Cu" "F.Mask" "F.Paste")
			(net "EXT_GPIO_2")
		)
		(pad "45" smd rect
			(at 2.02488 -11.24992)
			(size 1.54991 0.24994)
			(layers "F.Cu" "F.Mask" "F.Paste")
			(net "ANT4_IO_OUT")
		)
		(pad "46" smd rect
			(at -2.02489 -11.24992)
			(size 1.54991 0.24994)
			(layers "F.Cu" "F.Mask" "F.Paste")
			(net "EXT_GPIO_3")
		)
		(pad "47" smd rect
			(at 2.02488 -11.75004)
			(size 1.54991 0.24994)
			(layers "F.Cu" "F.Mask" "F.Paste")
			(net "ANT4_IO_IN")
		)
		(pad "48" smd rect
			(at -2.02489 -11.75004)
			(size 1.54991 0.24994)
			(layers "F.Cu" "F.Mask" "F.Paste")
			(net "EXT_GPIO_4")
		)
		(pad "49" smd rect
			(at 2.02488 -12.24992)
			(size 1.54991 0.24994)
			(layers "F.Cu" "F.Mask" "F.Paste")
			(net "GND")
		)
		(pad "50" smd rect
			(at -2.02489 -12.24992)
			(size 1.54991 0.24994)
			(layers "F.Cu" "F.Mask" "F.Paste")
			(net "GND")
		)
		(pad "51" smd rect
			(at 2.02488 -12.75004)
			(size 1.54991 0.24994)
			(layers "F.Cu" "F.Mask" "F.Paste")
		)
		(pad "52" smd rect
			(at -2.02489 -12.75004)
			(size 1.54991 0.24994)
			(layers "F.Cu" "F.Mask" "F.Paste")
		)
		(pad "53" smd rect
			(at 2.02488 -13.24991)
			(size 1.54991 0.24994)
			(layers "F.Cu" "F.Mask" "F.Paste")
		)
		(pad "54" smd rect
			(at -2.02489 -13.24991)
			(size 1.54991 0.24994)
			(layers "F.Cu" "F.Mask" "F.Paste")
		)
		(pad "55" smd rect
			(at 2.02488 -13.75004)
			(size 1.54991 0.24994)
			(layers "F.Cu" "F.Mask" "F.Paste")
		)
		(pad "56" smd rect
			(at -2.02489 -13.75004)
			(size 1.54991 0.24994)
			(layers "F.Cu" "F.Mask" "F.Paste")
		)
		(pad "57" smd rect
			(at 2.02488 -14.24991)
			(size 1.54991 0.24994)
			(layers "F.Cu" "F.Mask" "F.Paste")
		)
		(pad "58" smd rect
			(at -2.02489 -14.24991)
			(size 1.54991 0.24994)
			(layers "F.Cu" "F.Mask" "F.Paste")
		)
		(pad "59" smd rect
			(at 2.02488 -14.75004)
			(size 1.54991 0.24994)
			(layers "F.Cu" "F.Mask" "F.Paste")
			(net "GND")
		)
		(pad "60" smd rect
			(at -2.02489 -14.75004)
			(size 1.54991 0.24994)
			(layers "F.Cu" "F.Mask" "F.Paste")
			(net "GND")
		)
		(pad "61" smd rect
			(at 2.02488 -15.24991)
			(size 1.54991 0.24994)
			(layers "F.Cu" "F.Mask" "F.Paste")
		)
		(pad "62" smd rect
			(at -2.02489 -15.24991)
			(size 1.54991 0.24994)
			(layers "F.Cu" "F.Mask" "F.Paste")
		)
		(pad "63" smd rect
			(at 2.02488 -15.75004)
			(size 1.54991 0.24994)
			(layers "F.Cu" "F.Mask" "F.Paste")
		)
		(pad "64" smd rect
			(at -2.02489 -15.75004)
			(size 1.54991 0.24994)
			(layers "F.Cu" "F.Mask" "F.Paste")
		)
		(pad "65" smd rect
			(at 2.02488 -16.24991)
			(size 1.54991 0.24994)
			(layers "F.Cu" "F.Mask" "F.Paste")
		)
		(pad "66" smd rect
			(at -2.02489 -16.24991)
			(size 1.54991 0.24994)
			(layers "F.Cu" "F.Mask" "F.Paste")
		)
		(pad "67" smd rect
			(at 2.02488 -16.75003)
			(size 1.54991 0.24994)
			(layers "F.Cu" "F.Mask" "F.Paste")
		)
		(pad "68" smd rect
			(at -2.02489 -16.75003)
			(size 1.54991 0.24994)
			(layers "F.Cu" "F.Mask" "F.Paste")
		)
		(pad "69" smd rect
			(at 2.02488 -17.24991)
			(size 1.54991 0.24994)
			(layers "F.Cu" "F.Mask" "F.Paste")
			(net "GND")
		)
		(pad "70" smd rect
			(at -2.02489 -17.24991)
			(size 1.54991 0.24994)
			(layers "F.Cu" "F.Mask" "F.Paste")
			(net "GND")
		)
		(pad "71" smd rect
			(at 2.02488 -17.75003)
			(size 1.54991 0.24994)
			(layers "F.Cu" "F.Mask" "F.Paste")
		)
		(pad "72" smd rect
			(at -2.02489 -17.75003)
			(size 1.54991 0.24994)
			(layers "F.Cu" "F.Mask" "F.Paste")
		)
		(pad "73" smd rect
			(at 2.02488 -18.2499)
			(size 1.54991 0.24994)
			(layers "F.Cu" "F.Mask" "F.Paste")
		)
		(pad "74" smd rect
			(at -2.02489 -18.2499)
			(size 1.54991 0.24994)
			(layers "F.Cu" "F.Mask" "F.Paste")
		)
		(pad "75" smd rect
			(at 2.02488 -18.75003)
			(size 1.54991 0.24994)
			(layers "F.Cu" "F.Mask" "F.Paste")
		)
		(pad "76" smd rect
			(at -2.02489 -18.75003)
			(size 1.54991 0.24994)
			(layers "F.Cu" "F.Mask" "F.Paste")
		)
		(pad "77" smd rect
			(at 2.02488 -19.2499)
			(size 1.54991 0.24994)
			(layers "F.Cu" "F.Mask" "F.Paste")
			(net "FPGA_TCK")
		)
		(pad "78" smd rect
			(at -2.02489 -19.2499)
			(size 1.54991 0.24994)
			(layers "F.Cu" "F.Mask" "F.Paste")
			(net "FPGA_TDI")
		)
		(pad "79" smd rect
			(at 2.02488 -19.75003)
			(size 1.54991 0.24994)
			(layers "F.Cu" "F.Mask" "F.Paste")
			(net "FPGA_TDO")
		)
		(pad "80" smd rect
			(at -2.02489 -19.75003)
			(size 1.54991 0.24994)
			(layers "F.Cu" "F.Mask" "F.Paste")
			(net "FPGA_TMS")
		)
		(pad "81" smd rect
			(at 0.01135 1.17626)
			(size 1.70002 1.35001)
			(layers "F.Cu" "F.Mask" "F.Paste")
		)
		(pad "82" thru_hole circle
			(at 0 0)
			(size 0.55016 0.55016)
			(drill 0.55016)
			(layers "*.Cu" "*.Mask")
			(remove_unused_layers no)
			(thermal_bridge_angle 90)
		)
		(pad "83" thru_hole circle
			(at 0 -19.99996)
			(size 0.55016 0.55016)
			(drill 0.55016)
			(layers "*.Cu" "*.Mask")
			(remove_unused_layers no)
			(thermal_bridge_angle 90)
		)
		(pad "84" smd rect
			(at 0.01135 -21.17375)
			(size 1.70002 1.35001)
			(layers "F.Cu" "F.Mask" "F.Paste")
		)
	)
	(footprint "Vault:RESC1005X40X25NL10T10"
		(layer "F.Cu")
		(at 73.4216 114.7162)
		(property "Reference" "R30"
			(at -1 -0.906655 0)
			(unlocked yes)
			(layer "F.SilkS")
			(effects
				(font
					(size 0.762 0.762)
					(thickness 0.2286)
				)
				(justify left bottom)
			)
		)
		(property "Value" "4.7K_1%_0402"
			(at -0.4445 3.636645 0)
			(unlocked yes)
			(layer "F.SilkS")
			(hide yes)
			(effects
				(font
					(size 0.762 0.762)
					(thickness 0.2286)
				)
				(justify left bottom)
			)
		)
		(sheetname "01-USER_IO")
		(sheetfile "01-USER_IO.kicad_sch")
		(duplicate_pad_numbers_are_jumpers no)
		(pad "1" smd rect
			(at -0.425 0 90)
			(size 0.6 0.65)
			(layers "F.Cu" "F.Mask" "F.Paste")
			(net "+3.3V")
		)
		(pad "2" smd rect
			(at 0.425 0 90)
			(size 0.6 0.65)
			(layers "F.Cu" "F.Mask" "F.Paste")
			(net "ANT2_IO_IN")
		)
	)
	(footprint "Vault:RESC1005X40X25NL10T10"
		(layer "F.Cu")
		(at 170.3216 118.8162 -90)
		(property "Reference" "R119"
			(at 2.7032 0.242331 270)
			(unlocked yes)
			(layer "F.SilkS")
			(effects
				(font
					(size 0.762 0.762)
					(thickness 0.2032)
				)
			)
		)
		(property "Value" "4.7K_1%_0402"
			(at -2.732271 8.747465 180)
			(unlocked yes)
			(layer "F.SilkS")
			(hide yes)
			(effects
				(font
					(size 0.762 0.762)
					(thickness 0.2032)
				)
			)
		)
		(sheetname "08-DIPSwitches_I2C")
		(sheetfile "08-DIPSwitches_I2C.kicad_sch")
		(duplicate_pad_numbers_are_jumpers no)
		(pad "1" smd rect
			(at -0.425 0)
			(size 0.6 0.65)
			(layers "F.Cu" "F.Mask" "F.Paste")
			(net "MAC_I2C_SDA")
		)
		(pad "2" smd rect
			(at 0.425 0)
			(size 0.6 0.65)
			(layers "F.Cu" "F.Mask" "F.Paste")
			(net "+3.3V")
		)
	)
)
